FILE_TYPE = CONNECTIVITY;
{Allegro Design Entry HDL 16.6-p007 (v16-6-112F) 10/10/2012}
"PAGE_NUMBER" = 145;
0"NC";
1"GND\g";
2"GND\g";
3"P3V3_STBY\g";
4"GND\g";
5"GND\g";
6"GND\g";
7"GND\g";
8"GND\g";
9"GND\g";
10"GND\g";
11"GND\g";
12"FM_BIOS_TOP_SWAP";
13"IRQ_FORCE_NM_THROTTLE_N"CDS_PHYS_NET_NAME"IRQ_FORCE_NM_THROTTLE_N";
14"RST_BMC_SRST_N";
15"CLK_24M_25M_BMC_CLKIN";
16"TP_BMC_GPIOA2";
17"P2E_SSB_BMC_RX_DN";
18"FM_PWR_BTN_N";
19"RST_SYSTEM_BTN_N";
20"P2E_SSB_BMC_RX_C_DP";
21"P2E_SSB_BMC_RX_C_DN";
22"UART_BMC_RXD5";
23"RST_PLTRST_BUF_N_R";
24"CLK_100M_BMC_PE_R_DN";
25"P2E_SSB_BMC_TX_C_DP";
26"P2E_SSB_BMC_TX_C_DN";
27"SMB_PEHPCPU1_STBY_LVC3_SDA";
28"FM_BIOS_MRC_DEBUG_MSG_DIS_N"PHYS_NET_NAME"FM_BIOS_MRC_DEBUG_MSG_DIS_N"CDS_PHYS_NET_NAME"FM_BIOS_MRC_DEBUG_MSG_DIS_N";
29"FM_CPU1_THERMTRIP_LATCH_LVT3_N";
30"FM_OC_DETECT_EN_N"PHYS_NET_NAME"FM_OC_DETECT_EN_N"CDS_PHYS_NET_NAME"FM_OC_DETECT_EN_N";
31"IRQ_BOARD_BMC_ALERT_N"PHYS_NET_NAME"IRQ_BOARD_BMC_ALERT_N"CDS_PHYS_NET_NAME"IRQ_BOARD_BMC_ALERT_N";
32"FM_CPU1_RC_ERROR_N"PHYS_NET_NAME"FM_CPU1_RC_ERROR_N"CDS_PHYS_NET_NAME"FM_CPU1_RC_ERROR_N";
33"FM_CPU0_RC_ERROR_N";
34"SP1_BMC_HOST_UART_RX";
35"SP1_BMC_HOST_UART_TX";
36"FM_PMBUS_ALERT_BUF_EN_R3_N";
37"FM_MEM_THERM_EVENT_PCH_N";
38"IRQ_OC_DETECT_N";
39"IRQ_UV_DETECT_N";
40"IRQ_PVCCIN_CPU1_VRHOT_LVC3_N";
41"SPI_BMC_BT_WP0_N";
42"IRQ_PVDDQ_ABC_VRHOT_LVT3_N";
43"FM_OCP_MEZZC_PRES_LVT3_BMC";
44"FM_OCP_MEZZB_PRES_LVT3_BMC";
45"FM_PMBUS_ALERT_BUF_EN_N";
46"FM_HSC_TIMER_EXP_N";
47"FM_BATTERY_SENSE_EN_N";
48"IRQ_PVDDQ_KLM_VRHOT_LVT3_N";
49"SP2_BMC_CM_UART_TX";
50"SP2_BMC_CM_UART_RX";
51"FM_CPU0_THERMTRIP_LATCH_LVT3_N";
52"FM_CPU1_PROCHOT_LVT3_BMC_N";
53"RST_BMC_SYSRST_BTN_OUT_N";
54"FM_PWR_BTN_R1_N";
55"FM_CPU0_PROCHOT_LVT3_BMC_N";
56"CLK_100M_BMC_PE_R_DP";
57"FM_BMC_ONCTL_R_N";
58"FM_BMC_ONCTL_R_N";
59"PD_PEREXT";
60"CLK_25M_BMC";
61"CLK_24M_BMC_CLKIN_R";
62"FM_BMC_ONCTL_N";
63"SMB_DEBUG_STBY_LVC3_SCL";
64"FM_BOARD_REV_ID0";
65"FM_CPU_ERR1_LVT3_BMC_N";
66"FM_SOL_UART_CH_SEL"CDS_PHYS_NET_NAME"FM_SOL_UART_CH_SEL";
67"FM_BOARD_REV_ID1";
68"IRQ_DIMM_SAVE_LVT3_N"PHYS_NET_NAME"IRQ_DIMM_SAVE_LVT3_N"CDS_PHYS_NET_NAME"IRQ_DIMM_SAVE_LVT3_N";
69"FM_BOARD_REV_ID2";
70"SMB_PEHPCPU1_STBY_LVC3_SCL";
71"CLK_24M_25M_BMC_CLKIN";
72"PU_24M_OSC_OE";
73"SMB_PEHPCPU0_STBY_LVC3_R_SDA";
74"SMB_PEHPCPU0_STBY_LVC3_R2_SDA";
75"SMB_PEHPCPU0_STBY_LVC3_R2_SCL";
76"SMB_PEHPCPU0_STBY_LVC3_R_SCL";
77"SMB_DEBUG_STBY_LVC3_SDA";
78"SMB_PEHPCPU0_STBY_LVC3_SDA";
79"RST_PLTRST_BUF_N";
80"PECI_BMC";
81"IRQ_OOB_MGMT_RISER_ALERT_N"CDS_PHYS_NET_NAME"IRQ_OOB_MGMT_RISER_ALERT_N";
82"IRQ_MEZZ_LAN_ALERT_N"PHYS_NET_NAME"IRQ_MEZZ_LAN_ALERT_N"CDS_PHYS_NET_NAME"IRQ_MEZZ_LAN_ALERT_N";
83"FM_BIOS_SMI_ACTIVE_N";
84"SMB_DEBUG_STBY_LVC3_SCL_R";
85"SMB_DEBUG_STBY_LVC3_SDA_R";
86"SMB_PEHPCPU0_STBY_LVC3_SCL";
87"IRQ_PCH_NIC_ALERT_N";
88"FM_CPU_ERR0_LVT3_BMC_N";
89"P2E_SSB_BMC_RX_DP";
90"RST_SYSTEM_BTN_R_N";
91"FP_NMI_BTN_N";
92"IRQ_BMC_PCH_NMI_STBY_N";
93"FM_BMC_PWRBTN_OUT_N";
94"UART_BMC_TXD5";
95"IRQ_PVCCIN_CPU0_VRHOT_LVC3_N";
96"FM_BMC_SYS_THROTTLE_R_N"CDS_PHYS_NET_NAME"FM_BMC_SYS_THROTTLE_R_N";
97"FM_CPLD_BMC_PWRDN_N"PHYS_NET_NAME"FM_CPLD_BMC_PWRDN_N"CDS_PHYS_NET_NAME"FM_CPLD_BMC_PWRDN_N";
98"JTAG_RISER_N";
99"PECI_BMC_R";
%"RES"
"1","(-4450,-250)","0","mstr_discrete","I10";
;
PACK_TYPE"0402"
PART_NUMBER"G21497-005"
LOCATION"R9F60"
WATTAGE"1/16W"
VALUE"0.0"
MATERIAL"EMPTY"
TOLERANCE"5%"
CDS_SEC"1"
CDS_LOCATION"R9F60"
BOM_COST"SM_CONTROLLER"
SEC"1"
SEC_TYPE"0402"
ROOM"BMC"
CDS_LIB"mstr_discrete";
"B"
$PN"2"71;
"A"
$PN"1"60;
%"RES"
"1","(-7300,-3975)","0","mstr_discrete","I100";
;
CDS_SEC"1"
CDS_LOCATION"R1T15"
PACK_TYPE"0402"
WATTAGE"1/16W"
TOLERANCE"5%"
VALUE"0.0"
LOCATION"R1T15"
MATERIAL"EMPTY"
PART_NUMBER"G21497-005"
CDS_LIB"mstr_discrete"
SEC_TYPE"0402"
SEC"1";
"B"
$PN"2"57;
"A"
$PN"1"62;
%"RES"
"1","(-7050,-4200)","5","mstr_discrete","I101";
;
CDS_SEC"1"
CDS_LOCATION"R1T23"
LOCATION"R1T23"
TOLERANCE"5%"
MATERIAL"EMPTY"
VALUE"0.0"
WATTAGE"1/16W"
PACK_TYPE"0402"
PART_NUMBER"G21497-005"
SEC_TYPE"0402"
SEC"1"
CDS_LIB"mstr_discrete";
"B"
$PN"2"1;
"A"
$PN"1"57;
%"GND"
"1","(-7050,-4400)","0","mstr_symbols","I102";
;
HDL_POWER"GND"
BODY_TYPE"PLUMBING"
SIZE"1B"
VOLTAGE"0.0V"
CDS_LIB"mstr_symbols";
"A\NAC"1;
%"RES"
"1","(-4450,-550)","0","mstr_discrete","I11";
;
TOLERANCE"5%"
PACK_TYPE"0402"
PART_NUMBER"G21497-005"
LOCATION"R9F62"
VALUE"0.0"
WATTAGE"1/16W"
MATERIAL"CHIP"
CDS_SEC"1"
CDS_LOCATION"R9F62"
BOM_COST"SM_CONTROLLER"
ROOM"BMC"
SEC_TYPE"0402"
SEC"1"
CDS_LIB"mstr_discrete";
"B"
$PN"2"71;
"A"
$PN"1"61;
%"AST2520A1-GP-GP"
"3","(-3800,-2550)","0","w_hdl","I117";
;
CDS_SEC"3"
CDS_LOCATION"U25W4"
LOCATION"U25W4"
VALUE"AST2520A1-GP-GP"
CDS_LIB"w_hdl"
PART_NUMBER"071.2520A.M001"
CDS_LMAN_SYM_OUTLINE"-1150,1400,1150,-1400"
PACK_TYPE"ASIC2-GB1"
SEC"3"
SEC_TYPE"ASIC2-GB1";
"GPIOD5_SD2DAT3"
$PN"E20"69;
"GPIOD6_SD2CD# \B"
$PN"G18"88;
"GPIOL6_TXD1"
$PN"V1"35;
"GPIOF6_TXD4_LHSIRQ# \B"
$PN"G17"47;
"GPIOF4_NDTR4_LHCLK"
$PN"A21"48;
"GPIOF3_NRI4_LHAD3"
$PN"B21"40;
"GPIOL0_NCTS1"
$PN"T2"39;
"GPIOC5_SD1DAT3_SDA12"
$PN"E12"27;
"GPIOC7_SD1WP#_SDA13 \B"
$PN"B11"74;
"GPIOD7_SD2WP# \B"
$PN"C21"65;
"GPIOD2_SD2DAT0"
$PN"F20"66;
"GPIOD0_SD2CLK"
$PN"F19"28;
"GPIOE0_NCTS3"
$PN"B20"90;
"GPIOE1_NDCD3"
$PN"C20"53;
"GPIOE5_NRTS3"
$PN"D19"92;
"PETXP"
$PN"L21"89;
"PETXN"
$PN"L22"17;
"PEREXT"
$PN"K20"59;
"TXD5"
$PN"K1"94;
"GPIOE7_RXD3"
$PN"B19"52;
"GPIOE6_TXD3"
$PN"A20"55;
"GPIOE4_NDTR3"
$PN"E18"91;
"GPIOE3_NRI3"
$PN"F17"93;
"GPIOE2_NDSR3"
$PN"F18"54;
"GPIOF2_NDSR4_LHAD2"
$PN"B22"95;
"GPIOF1_NDCD4_LHAD1"
$PN"J18"41;
"GPIOF0_NCTS4_LHAD0"
$PN"J19"42;
"GPIOL7_RXD1"
$PN"W1"34;
"GPIOL5_NRTS1_VPICLK"
$PN"P3"36;
"GPIOL1_NDCD1_VPIDE"
$PN"T1"38;
"GPIOM7_RXD2_VPIB9"
$PN"T5"50;
"GPIOM6_TXD2_VPIB8"
$PN"R5"49;
"GPIOM5_NRTS2_VPIB7"
$PN"P5"29;
"GPIOM4_NDTR2_VPIB6"
$PN"AA2"51;
"GPIOM3_NRI2_VPIB5"
$PN"Y2"30;
"GPIOM2_NDSR2_VPIB4"
$PN"AA1"31;
"GPIOM1_NDCD2_VPIB3"
$PN"AB2"32;
"GPIOM0_NCTS2_VPIB2"
$PN"Y1"33;
"PERXP"
$PN"M21"25;
"PERXN"
$PN"M22"26;
"PERST# \B"
$PN"L20"23;
"GPIOA3_TIMER4"
$PN"E13"96;
"SRST# \B"
$PN"U18"14;
"CLKIN"
$PN"W18"15;
"GPIOD1_SD2CMD"
$PN"E21"64;
"GPIOD4_SD2DAT2"
$PN"D21"68;
"GPIOD3_SD2DAT1"
$PN"D20"67;
"PECI"
$PN"AB18"99;
"RXD5"
$PN"K2"22;
"PEREFCLKP"
$PN"K21"56;
"PEREFCLKN"
$PN"K22"24;
"GPIOL4_NDTR1_VPIVS"
$PN"P4"37;
"GPIOL3_NRI1_VPIHS"
$PN"U2"12;
"GPIOL2_NDSR1"
$PN"U1"46;
"GPIOF7_RXD4_LHRST# \B"
$PN"H18"43;
"GPIOF5_NRTS4_LHFRAME# \B"
$PN"H19"44;
"GPIOG4_SGPS2CK_SALT1"
$PN"E17"87;
"GPIOG5_SGPS2LD_SALT2"
$PN"D16"81;
"GPIOA2_TIMER3_SPI1CS1# \B"
$PN"D13"16;
"GPIOG7_SGPS2I1_SALT4"
$PN"E14"83;
"GPIOC4_SD1DAT2_SCL12"
$PN"D10"70;
"GPIOC6_SD1CD#_SCL13 \B"
$PN"C11"75;
"GPIOG6_SGPS2I0_SALT3"
$PN"D15"82;
"GPIOY3_SIOONCTRL# \B"
$PN"P21"58;
"GPIOA1_MAC2LINK"
$PN"D14"97;
"GPIOA0_MAC1LINK"
$PN"B14"98;
"GPIOC0_SD1CLK_SCL10"
$PN"C12"84;
"GPIOC1_SD1CMD_SDA10"
$PN"A12"85;
"GPIOC3_SD1DAT1_SDA11"
$PN"D9"78;
"GPIOC2_SD1DAT0_SCL11"
$PN"B12"86;
%"200R2F-L1-GP"
"1","(-1625,-3200)","1","w_hdl","I118";
;
CDS_SEC"1"
$SEC"1"
CDS_LOCATION"R25W67"
RATED"1/16W"
ATTRIBUTE"200 OHM"
TOLERANCE"1%"
PACK_SIZE"0402"
VALUE"200R2F-L1-GP"
LOCATION"R25W67"
GROUP"AST2500"
CDS_LMAN_SYM_OUTLINE"-50,75,50,-75"
CDS_LIB"w_hdl"
PART_NUMBER"64.20005.L0L"
PACK_TYPE"SMD-RG4";
"2"
$PN"2"11;
"1"
$PN"1"59;
%"RES"
"1","(-6450,-2300)","0","mstr_discrete","I119";
;
CDS_SEC"1"
CDS_LOCATION"R6W18"
TOLERANCE"5%"
LOCATION"R6W18"
VALUE"0.0"
MATERIAL"CHIP"
WATTAGE"1/16W"
PART_NUMBER"G21497-005"
PACK_TYPE"0402"
BOM_COST"MIO_USB"
ROOM"USB"
SEC_TYPE"0402"
SEC"1"
CDS_LIB"mstr_discrete";
"B"
$PN"2"85;
"A"
$PN"1"77;
%"RES"
"1","(-6450,-2350)","0","mstr_discrete","I120";
;
CDS_SEC"1"
CDS_LOCATION"R6W17"
TOLERANCE"5%"
PACK_TYPE"0402"
LOCATION"R6W17"
VALUE"0.0"
MATERIAL"CHIP"
WATTAGE"1/16W"
PART_NUMBER"G21497-005"
ROOM"USB"
BOM_COST"MIO_USB"
SEC_TYPE"0402"
SEC"1"
CDS_LIB"mstr_discrete";
"B"
$PN"2"84;
"A"
$PN"1"63;
%"GND"
"1","(-5275,-875)","0","mstr_symbols","I13";
;
HDL_POWER"GND"
BODY_TYPE"PLUMBING"
VOLTAGE"0.0V"
SIZE"1B"
CDS_LIB"mstr_symbols";
"A\NAC"2;
%"RES"
"1","(-6450,-2950)","0","mstr_discrete","I136";
;
TOLERANCE"1.0%"
WATTAGE"1/16W"
MATERIAL"CHIP"
PACK_TYPE"0402"
VALUE"22.1"
LOCATION"R2T41"
PART_NUMBER"G21796-250"
CDS_LOCATION"R2T41"
CDS_LIB"mstr_discrete"
ROOM"BMC"
BOM_COST"SM_CONTROLLER"
SEC_TYPE"0402"
SEC"1"
CDS_SEC"1";
"B"
$PN"2"96;
"A"
$PN"1"13;
%"RES"
"2","(-7000,-475)","0","mstr_discrete","I14";
;
PACK_TYPE"0402"
MATERIAL"CHIP"
TOLERANCE"1%"
VALUE"10.0K"
LOCATION"R9F61"
WATTAGE"1/16W"
PART_NUMBER"G21796-016"
CDS_SEC"1"
CDS_LOCATION"R9F61"
SEC"1"
BOM_COST"SM_CONTROLLER"
SEC_TYPE"0402"
ROOM"BMC"
CDS_LIB"mstr_discrete";
"A"
$PN"1"3;
"B"
$PN"2"72;
%"CAP_A"
"1","(-7500,-450)","0","dev_discrete","I15";
;
PART_NUMBER"A36096-030"
MATERIAL"X7R"
PACK_TYPE"0402V"
VOLTAGE"16V"
TOLERANCE"10%"
VALUE"0.1UF"
LOCATION"C9F23"
CDS_LOCATION"C9F23"
BOM_COST"SM_CONTROLLER"
SEC_TYPE"0402V"
ROOM"BMC"
CDS_SEC"1"
SEC"1"
CDS_LIB"dev_discrete";
"B"
$PN"2"4;
"A"
$PN"1"3;
%"CAP_A"
"1","(-1650,-3550)","1","dev_discrete","I158";
;
GROUP"AST2500"
PACK_TYPE"0402V"
MATERIAL"X7R"
PART_NUMBER"A36096-030"
LOCATION"C25W20"
VOLTAGE"16V"
TOLERANCE"10%"
VALUE"0.1UF"
CDS_LOCATION"C25W20"
SEC"1"
SEC_TYPE"0402V"
CDS_SEC"1"
CDS_LIB"dev_discrete"
BOM_COST"PROC_SIDEBAND"
ROOM"PROC_SIDEBAND";
"B"
$PN"2"20;
"A"
$PN"1"89;
%"CAP_A"
"1","(-1650,-3900)","1","dev_discrete","I159";
;
VALUE"0.1UF"
TOLERANCE"10%"
VOLTAGE"16V"
GROUP"AST2500"
PACK_TYPE"0402V"
MATERIAL"X7R"
LOCATION"C25W21"
PART_NUMBER"A36096-030"
SEC"1"
SEC_TYPE"0402V"
CDS_SEC"1"
CDS_LIB"dev_discrete"
BOM_COST"PROC_SIDEBAND"
ROOM"PROC_SIDEBAND"
CDS_LOCATION"C25W21";
"B"
$PN"2"21;
"A"
$PN"1"17;
%"P3V3_STBY"
"1","(-7500,-200)","0","mstr_symbols","I16";
;
HDL_POWER"P3V3_STBY"
BODY_TYPE"PLUMBING"
VOLTAGE"3.3V"
CDS_LIB"mstr_symbols"
SIZE"1B";
"G\NAC"3;
%"RES"
"1","(-5950,-3450)","0","mstr_discrete","I160";
;
CDS_SEC"1"
PART_NUMBER"G21497-005"
LOCATION"R25W141"
PACK_TYPE"0402"
VALUE"0.0"
TOLERANCE"5%"
GROUP"AST2500"
MATERIAL"CHIP"
WATTAGE"1/16W"
BOM_COST"PROC_SIDEBAND"
CDS_LIB"mstr_discrete"
SEC_TYPE"0402"
SEC"1"
ROOM"CPU0"
CDS_LOCATION"R25W141";
"B"
$PN"2"23;
"A"
$PN"1"79;
%"RES"
"1","(-6450,-1850)","0","mstr_discrete","I163";
;
CDS_SEC"1"
CDS_LOCATION"R25W121"
PART_NUMBER"G21796-173"
VALUE"20.0"
TOLERANCE"1%"
LOCATION"R25W121"
WATTAGE"1/16W"
MATERIAL"CHIP"
PACK_TYPE"0402"
SEC"1"
SEC_TYPE"0402"
CDS_LIB"mstr_discrete"
ROOM"SMB_PE_HP_CPU1";
"B"
$PN"2"74;
"A"
$PN"1"73;
%"RES"
"1","(-6450,-1900)","0","mstr_discrete","I164";
;
CDS_SEC"1"
CDS_LOCATION"R25W122"
MATERIAL"CHIP"
PACK_TYPE"0402"
LOCATION"R25W122"
VALUE"20.0"
TOLERANCE"1%"
WATTAGE"1/16W"
PART_NUMBER"G21796-173"
ROOM"SMB_PE_HP_CPU1"
CDS_LIB"mstr_discrete"
SEC_TYPE"0402"
SEC"1";
"B"
$PN"2"75;
"A"
$PN"1"76;
%"GND"
"1","(-7500,-675)","0","mstr_symbols","I17";
;
HDL_POWER"GND"
BODY_TYPE"PLUMBING"
CDS_LIB"mstr_symbols"
VOLTAGE"0.0V"
SIZE"1B";
"A\NAC"4;
%"RES"
"1","(-1500,-2900)","0","mstr_discrete","I173";
;
WATTAGE"1/16W"
MATERIAL"CHIP"
VALUE"0.0"
TOLERANCE"5%"
LOCATION"R25W144"
PART_NUMBER"G21497-005"
SEC_TYPE"0402"
CDS_LOCATION"R25W144"
CDS_LIB"mstr_discrete"
SEC"1"
ROOM"BMC"
BOM_COST"SM_CONTROLLER"
PACK_TYPE"0402"
CDS_SEC"1";
"B"
$PN"2"18;
"A"
$PN"1"54;
%"RES"
"1","(-1500,-3000)","0","mstr_discrete","I175";
;
WATTAGE"1/16W"
VALUE"0.0"
LOCATION"R25W145"
TOLERANCE"5%"
MATERIAL"CHIP"
PART_NUMBER"G21497-005"
SEC_TYPE"0402"
CDS_LOCATION"R25W145"
CDS_SEC"1"
PACK_TYPE"0402"
BOM_COST"SM_CONTROLLER"
ROOM"BMC"
SEC"1"
CDS_LIB"mstr_discrete";
"B"
$PN"2"19;
"A"
$PN"1"90;
%"RES"
"1","(-1500,-1850)","0","mstr_discrete","I176";
;
CDS_SEC"1"
LOCATION"R2W5"
VALUE"0.0"
TOLERANCE"5%"
PACK_TYPE"0402"
WATTAGE"1/16W"
PART_NUMBER"G21497-005"
SEC"1"
SEC_TYPE"0402"
ROOM"CPU0"
MATERIAL"CHIP"
BOM_COST"PROC_SIDEBAND"
CDS_LIB"mstr_discrete"
CDS_LOCATION"R2W5";
"B"
$PN"2"45;
"A"
$PN"1"36;
%"RES"
"1","(-6450,-3250)","0","mstr_discrete","I20";
;
PACK_TYPE"0402"
LOCATION"R9F33"
PART_NUMBER"G21497-005"
WATTAGE"1/16W"
MATERIAL"CHIP"
TOLERANCE"5%"
VALUE"0.0"
CDS_SEC"1"
BOM_COST"SM_CONTROLLER"
ROOM"BMC"
SEC_TYPE"0402"
SEC"1"
CDS_LIB"mstr_discrete"
CDS_LOCATION"R9F33";
"B"
$PN"2"99;
"A"
$PN"1"80;
%"RES"
"2","(-7650,-3425)","0","mstr_discrete","I22";
;
PACK_TYPE"0402"
MATERIAL"EMPTY"
LOCATION"R9F20"
VALUE"348"
TOLERANCE"1%"
WATTAGE"1/16W"
PART_NUMBER"G21796-340"
CDS_SEC"1"
BOM_COST"SM_CONTROLLER"
SEC"1"
SEC_TYPE"0402"
ROOM"BMC"
CDS_LOCATION"R9F20"
CDS_LIB"mstr_discrete";
"A"
$PN"1"80;
"B"
$PN"2"5;
%"GND"
"1","(-7650,-3625)","0","mstr_symbols","I23";
;
VOLTAGE"0.0V"
SIZE"1B"
CDS_LIB"mstr_symbols"
BODY_TYPE"PLUMBING"
HDL_POWER"GND";
"A\NAC"5;
%"RES"
"2","(-5450,-4150)","0","mstr_discrete","I30";
;
GROUP"AST2520"
PACK_TYPE"0402"
WATTAGE"1/16W"
MATERIAL"CHIP"
TOLERANCE"1%"
VALUE"100.0K"
LOCATION"R25W61"
PART_NUMBER"G21796-010"
ROOM"BMC"
BOM_COST"SM_CONTROLLER"
SEC_TYPE"0402"
SEC"1"
CDS_LIB"mstr_discrete"
CDS_SEC"1"
CDS_LOCATION"R25W61";
"A"
$PN"1"56;
"B"
$PN"2"7;
%"RES"
"2","(-5200,-4150)","0","mstr_discrete","I31";
;
GROUP"AST2520"
PACK_TYPE"0402"
PART_NUMBER"G21796-010"
TOLERANCE"1%"
VALUE"100.0K"
LOCATION"R25W62"
MATERIAL"CHIP"
WATTAGE"1/16W"
CDS_SEC"1"
CDS_LIB"mstr_discrete"
SEC"1"
SEC_TYPE"0402"
BOM_COST"SM_CONTROLLER"
ROOM"BMC"
CDS_LOCATION"R25W62";
"A"
$PN"1"23;
"B"
$PN"2"6;
%"GND"
"1","(-5200,-4350)","0","mstr_symbols","I32";
;
HDL_POWER"GND"
BODY_TYPE"PLUMBING"
SIZE"1B"
VOLTAGE"0.0V"
CDS_LIB"mstr_symbols";
"A\NAC"6;
%"GND"
"1","(-5450,-4350)","0","mstr_symbols","I33";
;
HDL_POWER"GND"
BODY_TYPE"PLUMBING"
SIZE"1B"
VOLTAGE"0.0V"
CDS_LIB"mstr_symbols";
"A\NAC"7;
%"RES"
"2","(-5700,-4150)","0","mstr_discrete","I34";
;
GROUP"AST2520"
LOCATION"R25W60"
VALUE"100.0K"
WATTAGE"1/16W"
MATERIAL"CHIP"
TOLERANCE"1%"
PART_NUMBER"G21796-010"
PACK_TYPE"0402"
BOM_COST"SM_CONTROLLER"
ROOM"BMC"
SEC_TYPE"0402"
SEC"1"
CDS_LIB"mstr_discrete"
CDS_SEC"1"
CDS_LOCATION"R25W60";
"A"
$PN"1"24;
"B"
$PN"2"8;
%"GND"
"1","(-5700,-4350)","0","mstr_symbols","I35";
;
HDL_POWER"GND"
BODY_TYPE"PLUMBING"
SIZE"1B"
CDS_LIB"mstr_symbols"
VOLTAGE"0.0V";
"A\NAC"8;
%"RES"
"2","(-5950,-4150)","0","mstr_discrete","I36";
;
GROUP"AST2520"
WATTAGE"1/16W"
PART_NUMBER"G21796-010"
PACK_TYPE"0402"
LOCATION"R25W64"
TOLERANCE"1%"
MATERIAL"CHIP"
VALUE"100.0K"
ROOM"BMC"
BOM_COST"SM_CONTROLLER"
SEC"1"
SEC_TYPE"0402"
CDS_LIB"mstr_discrete"
CDS_SEC"1"
CDS_LOCATION"R25W64";
"A"
$PN"1"25;
"B"
$PN"2"9;
%"GND"
"1","(-5950,-4350)","0","mstr_symbols","I37";
;
HDL_POWER"GND"
BODY_TYPE"PLUMBING"
SIZE"1B"
VOLTAGE"0.0V"
CDS_LIB"mstr_symbols";
"A\NAC"9;
%"RES"
"2","(-6200,-4150)","0","mstr_discrete","I38";
;
GROUP"AST2520"
PACK_TYPE"0402"
PART_NUMBER"G21796-010"
MATERIAL"CHIP"
WATTAGE"1/16W"
TOLERANCE"1%"
VALUE"100.0K"
LOCATION"R25W65"
CDS_SEC"1"
CDS_LIB"mstr_discrete"
SEC_TYPE"0402"
SEC"1"
BOM_COST"SM_CONTROLLER"
ROOM"BMC"
CDS_LOCATION"R25W65";
"A"
$PN"1"26;
"B"
$PN"2"10;
%"GND"
"1","(-6200,-4350)","0","mstr_symbols","I39";
;
HDL_POWER"GND"
BODY_TYPE"PLUMBING"
SIZE"1B"
VOLTAGE"0.0V"
CDS_LIB"mstr_symbols";
"A\NAC"10;
%"GND"
"1","(-1400,-3200)","1","mstr_symbols","I47";
;
HDL_POWER"GND"
BODY_TYPE"PLUMBING"
VOLTAGE"0.0V"
CDS_LIB"mstr_symbols"
SIZE"1B";
"A\NAC"11;
%"OSC_C"
"11","(-5750,-650)","0","mstr_discrete","I8";
;
LOCATION"Y9F2"
MATERIAL"OSC"
VALUE"24MHZ"
PART_NUMBER"D34520-021"
CDS_SEC"1"
CDS_LOCATION"Y9F2"
CDS_LMAN_SYM_OUTLINE"-350,200,350,-200"
CDS_LIB"mstr_discrete"
ROOM"BMC"
SEC_TYPE"SM4"
BOM_COST"SM_CONTROLLER"
SEC"1"
PACK_TYPE"SM4";
"ENABLE_CONTROL"
$PN"1"72;
"VDD"
$PN"4"3;
"GND"
$PN"2"2;
"OUT"
$PN"3"61;
END.
